(kicad_pcb
	(version 20241229)
	(generator "pcbnew")
	(generator_version "9.0")
	(general
		(thickness 1.599998)
		(legacy_teardrops no)
	)
	(paper "A4")
	(title_block
		(title "Artix - Datacenter Secure Control Module (DC-SCM)")
		(date "2024-11-06")
		(rev "1.1.3")
		(comment 9 "footprints 82-86 of 544")
	)
	(layers
		(0 "F.Cu" signal)
		(4 "In1.Cu" signal)
		(6 "In2.Cu" signal)
		(8 "In3.Cu" signal)
		(10 "In4.Cu" signal)
		(12 "In5.Cu" signal)
		(14 "In6.Cu" signal)
		(2 "B.Cu" signal)
		(9 "F.Adhes" user "F.Adhesive")
		(11 "B.Adhes" user "B.Adhesive")
		(13 "F.Paste" user)
		(15 "B.Paste" user)
		(5 "F.SilkS" user "F.Silkscreen")
		(7 "B.SilkS" user "B.Silkscreen")
		(1 "F.Mask" user)
		(3 "B.Mask" user)
		(17 "Dwgs.User" user "User.Drawings")
		(19 "Cmts.User" user "User.Comments")
		(21 "Eco1.User" user "User.Eco1")
		(23 "Eco2.User" user "User.Eco2")
		(25 "Edge.Cuts" user)
		(27 "Margin" user)
		(31 "F.CrtYd" user "F.Courtyard")
		(29 "B.CrtYd" user "B.Courtyard")
		(35 "F.Fab" user)
		(33 "B.Fab" user)
	)
	(footprint "antmicro-footprints:C_0402_1005Metric"
		(layer "F.Cu")
		(at 98.774 140.075 -90)
		(descr "Capacitor SMD 0402")
		(tags "capacitor SMD 0402")
		(property "Reference" "C59"
			(at -2.975 -0.326 90)
			(layer "F.SilkS")
			(effects
				(font
					(size 0.7 0.7)
					(thickness 0.15)
				)
				(justify right bottom)
			)
		)
		(property "Value" "C_470n_0402"
			(at 0 1.4 90)
			(layer "F.Fab")
			(effects
				(font
					(size 0.7 0.7)
					(thickness 0.15)
				)
				(justify right bottom)
			)
		)
		(property "Datasheet" "https://product.tdk.com/en/search/capacitor/ceramic/mlcc/info?part_no=C1005X5R1E474M050BB"
			(at 0 0 270)
			(layer "F.Fab")
			(hide yes)
			(effects
				(font
					(size 1.27 1.27)
					(thickness 0.15)
				)
			)
		)
		(property "Description" "SMD Multilayer Ceramic Capacitor, 0.47 µF, 25 V, 0402 [1005 Metric], ± 20%, X5R, C"
			(at 0 0 270)
			(layer "F.Fab")
			(hide yes)
			(effects
				(font
					(size 1.27 1.27)
					(thickness 0.15)
				)
			)
		)
		(property "Author" "Antmicro"
			(at -41.301 238.849 0)
			(layer "F.Fab")
			(hide yes)
			(effects
				(font
					(size 1 1)
					(thickness 0.15)
				)
			)
		)
		(property "Dielectric" ""
			(at -41.301 238.849 0)
			(layer "F.Fab")
			(hide yes)
			(effects
				(font
					(size 1 1)
					(thickness 0.15)
				)
			)
		)
		(property "License" "Apache-2.0"
			(at -41.301 238.849 0)
			(layer "F.Fab")
			(hide yes)
			(effects
				(font
					(size 1 1)
					(thickness 0.15)
				)
			)
		)
		(property "MPN" "C1005X5R1E474M050BB"
			(at -41.301 238.849 0)
			(layer "F.Fab")
			(hide yes)
			(effects
				(font
					(size 1 1)
					(thickness 0.15)
				)
			)
		)
		(property "Manufacturer" "TDK"
			(at -41.301 238.849 0)
			(layer "F.Fab")
			(hide yes)
			(effects
				(font
					(size 1 1)
					(thickness 0.15)
				)
			)
		)
		(property "Val" "470n"
			(at -41.301 238.849 0)
			(layer "F.Fab")
			(hide yes)
			(effects
				(font
					(size 1 1)
					(thickness 0.15)
				)
			)
		)
		(property "Voltage" ""
			(at -41.301 238.849 0)
			(layer "F.Fab")
			(hide yes)
			(effects
				(font
					(size 1 1)
					(thickness 0.15)
				)
			)
		)
		(sheetname "/DDR3/")
		(sheetfile "ddr3.kicad_sch")
		(attr smd)
		(fp_rect
			(start -0.925 -0.47)
			(end 0.925 0.47)
			(stroke
				(width 0.05)
				(type default)
			)
			(fill no)
			(layer "F.CrtYd")
		)
		(fp_line
			(start -0.494 0.248)
			(end -0.494 -0.25)
			(stroke
				(width 0.15)
				(type solid)
			)
			(layer "F.Fab")
		)
		(fp_line
			(start 0.504 0.248)
			(end -0.494 0.248)
			(stroke
				(width 0.15)
				(type solid)
			)
			(layer "F.Fab")
		)
		(fp_line
			(start -0.494 -0.25)
			(end 0.504 -0.25)
			(stroke
				(width 0.15)
				(type solid)
			)
			(layer "F.Fab")
		)
		(fp_line
			(start 0.504 -0.25)
			(end 0.504 0.248)
			(stroke
				(width 0.15)
				(type solid)
			)
			(layer "F.Fab")
		)
		(pad "1" smd roundrect
			(at -0.48 0 270)
			(size 0.59 0.64)
			(layers "F.Cu" "F.Mask" "F.Paste")
			(roundrect_rratio 0.25)
			(net 1 "GND")
			(pintype "passive")
		)
		(pad "2" smd roundrect
			(at 0.48 0 270)
			(size 0.59 0.64)
			(layers "F.Cu" "F.Mask" "F.Paste")
			(roundrect_rratio 0.25)
			(net 3 "VCC1V35")
			(pintype "passive")
		)
	)
	(footprint "antmicro-footprints:C_0402_1005Metric"
		(layer "F.Cu")
		(at 97.774 140.075 -90)
		(descr "Capacitor SMD 0402")
		(tags "capacitor SMD 0402")
		(property "Reference" "C53"
			(at -2.975 -0.326 90)
			(layer "F.SilkS")
			(effects
				(font
					(size 0.7 0.7)
					(thickness 0.15)
				)
				(justify right bottom)
			)
		)
		(property "Value" "C_470n_0402"
			(at 0 1.4 90)
			(layer "F.Fab")
			(effects
				(font
					(size 0.7 0.7)
					(thickness 0.15)
				)
				(justify right bottom)
			)
		)
		(property "Datasheet" "https://product.tdk.com/en/search/capacitor/ceramic/mlcc/info?part_no=C1005X5R1E474M050BB"
			(at 0 0 270)
			(layer "F.Fab")
			(hide yes)
			(effects
				(font
					(size 1.27 1.27)
					(thickness 0.15)
				)
			)
		)
		(property "Description" "SMD Multilayer Ceramic Capacitor, 0.47 µF, 25 V, 0402 [1005 Metric], ± 20%, X5R, C"
			(at 0 0 270)
			(layer "F.Fab")
			(hide yes)
			(effects
				(font
					(size 1.27 1.27)
					(thickness 0.15)
				)
			)
		)
		(property "Author" "Antmicro"
			(at -42.301 237.849 0)
			(layer "F.Fab")
			(hide yes)
			(effects
				(font
					(size 1 1)
					(thickness 0.15)
				)
			)
		)
		(property "Dielectric" ""
			(at -42.301 237.849 0)
			(layer "F.Fab")
			(hide yes)
			(effects
				(font
					(size 1 1)
					(thickness 0.15)
				)
			)
		)
		(property "License" "Apache-2.0"
			(at -42.301 237.849 0)
			(layer "F.Fab")
			(hide yes)
			(effects
				(font
					(size 1 1)
					(thickness 0.15)
				)
			)
		)
		(property "MPN" "C1005X5R1E474M050BB"
			(at -42.301 237.849 0)
			(layer "F.Fab")
			(hide yes)
			(effects
				(font
					(size 1 1)
					(thickness 0.15)
				)
			)
		)
		(property "Manufacturer" "TDK"
			(at -42.301 237.849 0)
			(layer "F.Fab")
			(hide yes)
			(effects
				(font
					(size 1 1)
					(thickness 0.15)
				)
			)
		)
		(property "Val" "470n"
			(at -42.301 237.849 0)
			(layer "F.Fab")
			(hide yes)
			(effects
				(font
					(size 1 1)
					(thickness 0.15)
				)
			)
		)
		(property "Voltage" ""
			(at -42.301 237.849 0)
			(layer "F.Fab")
			(hide yes)
			(effects
				(font
					(size 1 1)
					(thickness 0.15)
				)
			)
		)
		(sheetname "/DDR3/")
		(sheetfile "ddr3.kicad_sch")
		(attr smd)
		(fp_rect
			(start -0.925 -0.47)
			(end 0.925 0.47)
			(stroke
				(width 0.05)
				(type default)
			)
			(fill no)
			(layer "F.CrtYd")
		)
		(fp_line
			(start -0.494 0.248)
			(end -0.494 -0.25)
			(stroke
				(width 0.15)
				(type solid)
			)
			(layer "F.Fab")
		)
		(fp_line
			(start 0.504 0.248)
			(end -0.494 0.248)
			(stroke
				(width 0.15)
				(type solid)
			)
			(layer "F.Fab")
		)
		(fp_line
			(start -0.494 -0.25)
			(end 0.504 -0.25)
			(stroke
				(width 0.15)
				(type solid)
			)
			(layer "F.Fab")
		)
		(fp_line
			(start 0.504 -0.25)
			(end 0.504 0.248)
			(stroke
				(width 0.15)
				(type solid)
			)
			(layer "F.Fab")
		)
		(pad "1" smd roundrect
			(at -0.48 0 270)
			(size 0.59 0.64)
			(layers "F.Cu" "F.Mask" "F.Paste")
			(roundrect_rratio 0.25)
			(net 1 "GND")
			(pintype "passive")
		)
		(pad "2" smd roundrect
			(at 0.48 0 270)
			(size 0.59 0.64)
			(layers "F.Cu" "F.Mask" "F.Paste")
			(roundrect_rratio 0.25)
			(net 3 "VCC1V35")
			(pintype "passive")
		)
	)
	(footprint "antmicro-footprints:C_0402_1005Metric"
		(layer "F.Cu")
		(at 95.674 140.075 -90)
		(descr "Capacitor SMD 0402")
		(tags "capacitor SMD 0402")
		(property "Reference" "C60"
			(at -2.975 -0.326 90)
			(layer "F.SilkS")
			(effects
				(font
					(size 0.7 0.7)
					(thickness 0.15)
				)
				(justify right bottom)
			)
		)
		(property "Value" "C_470n_0402"
			(at 0 1.4 90)
			(layer "F.Fab")
			(effects
				(font
					(size 0.7 0.7)
					(thickness 0.15)
				)
				(justify right bottom)
			)
		)
		(property "Datasheet" "https://product.tdk.com/en/search/capacitor/ceramic/mlcc/info?part_no=C1005X5R1E474M050BB"
			(at 0 0 270)
			(layer "F.Fab")
			(hide yes)
			(effects
				(font
					(size 1.27 1.27)
					(thickness 0.15)
				)
			)
		)
		(property "Description" "SMD Multilayer Ceramic Capacitor, 0.47 µF, 25 V, 0402 [1005 Metric], ± 20%, X5R, C"
			(at 0 0 270)
			(layer "F.Fab")
			(hide yes)
			(effects
				(font
					(size 1.27 1.27)
					(thickness 0.15)
				)
			)
		)
		(property "Author" "Antmicro"
			(at -44.401 235.749 0)
			(layer "F.Fab")
			(hide yes)
			(effects
				(font
					(size 1 1)
					(thickness 0.15)
				)
			)
		)
		(property "Dielectric" ""
			(at -44.401 235.749 0)
			(layer "F.Fab")
			(hide yes)
			(effects
				(font
					(size 1 1)
					(thickness 0.15)
				)
			)
		)
		(property "License" "Apache-2.0"
			(at -44.401 235.749 0)
			(layer "F.Fab")
			(hide yes)
			(effects
				(font
					(size 1 1)
					(thickness 0.15)
				)
			)
		)
		(property "MPN" "C1005X5R1E474M050BB"
			(at -44.401 235.749 0)
			(layer "F.Fab")
			(hide yes)
			(effects
				(font
					(size 1 1)
					(thickness 0.15)
				)
			)
		)
		(property "Manufacturer" "TDK"
			(at -44.401 235.749 0)
			(layer "F.Fab")
			(hide yes)
			(effects
				(font
					(size 1 1)
					(thickness 0.15)
				)
			)
		)
		(property "Val" "470n"
			(at -44.401 235.749 0)
			(layer "F.Fab")
			(hide yes)
			(effects
				(font
					(size 1 1)
					(thickness 0.15)
				)
			)
		)
		(property "Voltage" ""
			(at -44.401 235.749 0)
			(layer "F.Fab")
			(hide yes)
			(effects
				(font
					(size 1 1)
					(thickness 0.15)
				)
			)
		)
		(sheetname "/DDR3/")
		(sheetfile "ddr3.kicad_sch")
		(attr smd)
		(fp_rect
			(start -0.925 -0.47)
			(end 0.925 0.47)
			(stroke
				(width 0.05)
				(type default)
			)
			(fill no)
			(layer "F.CrtYd")
		)
		(fp_line
			(start -0.494 0.248)
			(end -0.494 -0.25)
			(stroke
				(width 0.15)
				(type solid)
			)
			(layer "F.Fab")
		)
		(fp_line
			(start 0.504 0.248)
			(end -0.494 0.248)
			(stroke
				(width 0.15)
				(type solid)
			)
			(layer "F.Fab")
		)
		(fp_line
			(start -0.494 -0.25)
			(end 0.504 -0.25)
			(stroke
				(width 0.15)
				(type solid)
			)
			(layer "F.Fab")
		)
		(fp_line
			(start 0.504 -0.25)
			(end 0.504 0.248)
			(stroke
				(width 0.15)
				(type solid)
			)
			(layer "F.Fab")
		)
		(pad "1" smd roundrect
			(at -0.48 0 270)
			(size 0.59 0.64)
			(layers "F.Cu" "F.Mask" "F.Paste")
			(roundrect_rratio 0.25)
			(net 1 "GND")
			(pintype "passive")
		)
		(pad "2" smd roundrect
			(at 0.48 0 270)
			(size 0.59 0.64)
			(layers "F.Cu" "F.Mask" "F.Paste")
			(roundrect_rratio 0.25)
			(net 3 "VCC1V35")
			(pintype "passive")
		)
	)
	(footprint "antmicro-footprints:C_0402_1005Metric"
		(layer "F.Cu")
		(at 96.174 154.675 90)
		(descr "Capacitor SMD 0402")
		(tags "capacitor SMD 0402")
		(property "Reference" "C61"
			(at -3.425 -8.074 90)
			(layer "F.SilkS")
			(effects
				(font
					(size 0.7 0.7)
					(thickness 0.15)
				)
				(justify left bottom)
			)
		)
		(property "Value" "C_470n_0402"
			(at 0 1.4 90)
			(layer "F.Fab")
			(effects
				(font
					(size 0.7 0.7)
					(thickness 0.15)
				)
				(justify left bottom)
			)
		)
		(property "Datasheet" "https://product.tdk.com/en/search/capacitor/ceramic/mlcc/info?part_no=C1005X5R1E474M050BB"
			(at 0 0 90)
			(layer "F.Fab")
			(hide yes)
			(effects
				(font
					(size 1.27 1.27)
					(thickness 0.15)
				)
			)
		)
		(property "Description" "SMD Multilayer Ceramic Capacitor, 0.47 µF, 25 V, 0402 [1005 Metric], ± 20%, X5R, C"
			(at 0 0 90)
			(layer "F.Fab")
			(hide yes)
			(effects
				(font
					(size 1.27 1.27)
					(thickness 0.15)
				)
			)
		)
		(property "Author" "Antmicro"
			(at 250.849 58.501 0)
			(layer "F.Fab")
			(hide yes)
			(effects
				(font
					(size 1 1)
					(thickness 0.15)
				)
			)
		)
		(property "Dielectric" ""
			(at 250.849 58.501 0)
			(layer "F.Fab")
			(hide yes)
			(effects
				(font
					(size 1 1)
					(thickness 0.15)
				)
			)
		)
		(property "License" "Apache-2.0"
			(at 250.849 58.501 0)
			(layer "F.Fab")
			(hide yes)
			(effects
				(font
					(size 1 1)
					(thickness 0.15)
				)
			)
		)
		(property "MPN" "C1005X5R1E474M050BB"
			(at 250.849 58.501 0)
			(layer "F.Fab")
			(hide yes)
			(effects
				(font
					(size 1 1)
					(thickness 0.15)
				)
			)
		)
		(property "Manufacturer" "TDK"
			(at 250.849 58.501 0)
			(layer "F.Fab")
			(hide yes)
			(effects
				(font
					(size 1 1)
					(thickness 0.15)
				)
			)
		)
		(property "Val" "470n"
			(at 250.849 58.501 0)
			(layer "F.Fab")
			(hide yes)
			(effects
				(font
					(size 1 1)
					(thickness 0.15)
				)
			)
		)
		(property "Voltage" ""
			(at 250.849 58.501 0)
			(layer "F.Fab")
			(hide yes)
			(effects
				(font
					(size 1 1)
					(thickness 0.15)
				)
			)
		)
		(sheetname "/DDR3/")
		(sheetfile "ddr3.kicad_sch")
		(attr smd)
		(fp_rect
			(start -0.925 -0.47)
			(end 0.925 0.47)
			(stroke
				(width 0.05)
				(type default)
			)
			(fill no)
			(layer "F.CrtYd")
		)
		(fp_line
			(start 0.504 -0.25)
			(end 0.504 0.248)
			(stroke
				(width 0.15)
				(type solid)
			)
			(layer "F.Fab")
		)
		(fp_line
			(start -0.494 -0.25)
			(end 0.504 -0.25)
			(stroke
				(width 0.15)
				(type solid)
			)
			(layer "F.Fab")
		)
		(fp_line
			(start 0.504 0.248)
			(end -0.494 0.248)
			(stroke
				(width 0.15)
				(type solid)
			)
			(layer "F.Fab")
		)
		(fp_line
			(start -0.494 0.248)
			(end -0.494 -0.25)
			(stroke
				(width 0.15)
				(type solid)
			)
			(layer "F.Fab")
		)
		(pad "1" smd roundrect
			(at -0.48 0 90)
			(size 0.59 0.64)
			(layers "F.Cu" "F.Mask" "F.Paste")
			(roundrect_rratio 0.25)
			(net 1 "GND")
			(pintype "passive")
		)
		(pad "2" smd roundrect
			(at 0.48 0 90)
			(size 0.59 0.64)
			(layers "F.Cu" "F.Mask" "F.Paste")
			(roundrect_rratio 0.25)
			(net 3 "VCC1V35")
			(pintype "passive")
		)
	)
	(footprint "antmicro-footprints:C_0402_1005Metric"
		(layer "F.Cu")
		(at 97.374 154.675 90)
		(descr "Capacitor SMD 0402")
		(tags "capacitor SMD 0402")
		(property "Reference" "C54"
			(at -3.425 -8.174 90)
			(layer "F.SilkS")
			(effects
				(font
					(size 0.7 0.7)
					(thickness 0.15)
				)
				(justify left bottom)
			)
		)
		(property "Value" "C_470n_0402"
			(at 0 1.4 90)
			(layer "F.Fab")
			(effects
				(font
					(size 0.7 0.7)
					(thickness 0.15)
				)
				(justify left bottom)
			)
		)
		(property "Datasheet" "https://product.tdk.com/en/search/capacitor/ceramic/mlcc/info?part_no=C1005X5R1E474M050BB"
			(at 0 0 90)
			(layer "F.Fab")
			(hide yes)
			(effects
				(font
					(size 1.27 1.27)
					(thickness 0.15)
				)
			)
		)
		(property "Description" "SMD Multilayer Ceramic Capacitor, 0.47 µF, 25 V, 0402 [1005 Metric], ± 20%, X5R, C"
			(at 0 0 90)
			(layer "F.Fab")
			(hide yes)
			(effects
				(font
					(size 1.27 1.27)
					(thickness 0.15)
				)
			)
		)
		(property "Author" "Antmicro"
			(at 252.049 57.301 0)
			(layer "F.Fab")
			(hide yes)
			(effects
				(font
					(size 1 1)
					(thickness 0.15)
				)
			)
		)
		(property "Dielectric" ""
			(at 252.049 57.301 0)
			(layer "F.Fab")
			(hide yes)
			(effects
				(font
					(size 1 1)
					(thickness 0.15)
				)
			)
		)
		(property "License" "Apache-2.0"
			(at 252.049 57.301 0)
			(layer "F.Fab")
			(hide yes)
			(effects
				(font
					(size 1 1)
					(thickness 0.15)
				)
			)
		)
		(property "MPN" "C1005X5R1E474M050BB"
			(at 252.049 57.301 0)
			(layer "F.Fab")
			(hide yes)
			(effects
				(font
					(size 1 1)
					(thickness 0.15)
				)
			)
		)
		(property "Manufacturer" "TDK"
			(at 252.049 57.301 0)
			(layer "F.Fab")
			(hide yes)
			(effects
				(font
					(size 1 1)
					(thickness 0.15)
				)
			)
		)
		(property "Val" "470n"
			(at 252.049 57.301 0)
			(layer "F.Fab")
			(hide yes)
			(effects
				(font
					(size 1 1)
					(thickness 0.15)
				)
			)
		)
		(property "Voltage" ""
			(at 252.049 57.301 0)
			(layer "F.Fab")
			(hide yes)
			(effects
				(font
					(size 1 1)
					(thickness 0.15)
				)
			)
		)
		(sheetname "/DDR3/")
		(sheetfile "ddr3.kicad_sch")
		(attr smd)
		(fp_rect
			(start -0.925 -0.47)
			(end 0.925 0.47)
			(stroke
				(width 0.05)
				(type default)
			)
			(fill no)
			(layer "F.CrtYd")
		)
		(fp_line
			(start 0.504 -0.25)
			(end 0.504 0.248)
			(stroke
				(width 0.15)
				(type solid)
			)
			(layer "F.Fab")
		)
		(fp_line
			(start -0.494 -0.25)
			(end 0.504 -0.25)
			(stroke
				(width 0.15)
				(type solid)
			)
			(layer "F.Fab")
		)
		(fp_line
			(start 0.504 0.248)
			(end -0.494 0.248)
			(stroke
				(width 0.15)
				(type solid)
			)
			(layer "F.Fab")
		)
		(fp_line
			(start -0.494 0.248)
			(end -0.494 -0.25)
			(stroke
				(width 0.15)
				(type solid)
			)
			(layer "F.Fab")
		)
		(pad "1" smd roundrect
			(at -0.48 0 90)
			(size 0.59 0.64)
			(layers "F.Cu" "F.Mask" "F.Paste")
			(roundrect_rratio 0.25)
			(net 1 "GND")
			(pintype "passive")
		)
		(pad "2" smd roundrect
			(at 0.48 0 90)
			(size 0.59 0.64)
			(layers "F.Cu" "F.Mask" "F.Paste")
			(roundrect_rratio 0.25)
			(net 3 "VCC1V35")
			(pintype "passive")
		)
	)
)
